# T6G (Grand Teton) — schematic netlist excerpt (pin names and nets, part order shuffled) for the footprints in the layout excerpt that follows; sources: Cadence DE-HDL packaged netlist, KiCad conversion of 04192023_DAF0TMB3IC0_F0TG_MB_C_brd_V02_OCP.brd

C7504  Q_CAP  0.1UF 10V 10% X7S  pkg C0201  page 355 : A = P1V8_CPU1_RT_1D ; B = GND
PC113_4  Q_CAP  0.1UF 25V 10% X7R  pkg 0402  page 202 : A = PVDDCR_CPU1_P0_VCCS ; B = GND
R3975  Q_RES  0 5% CHIP  pkg 0402LF  page 146 : A = P12V_E1S_SENSE_0 ; B = P12V_E1S_0_ISENSE_MAM_TIC

(kicad_pcb
	(version 20260206)
	(generator "pcbnew")
	(generator_version "10.0")
	(general
		(thickness 1.6)
		(legacy_teardrops no)
	)
	(paper "A4")
	(title_block
		(title "04192023_DAF0TMB3IC0_F0TG_MB_C_brd_V02_OCP.brd")
		(comment 1 "Grand Teton / footprints 1573-1575 of 8354")
	)
	(layers
		(0 "F.Cu" signal "TOP")
		(4 "In1.Cu" signal "GND")
		(6 "In2.Cu" signal "IN1")
		(8 "In3.Cu" signal "GND1")
		(10 "In4.Cu" signal "IN2")
		(12 "In5.Cu" signal "GND2")
		(14 "In6.Cu" signal "IN3")
		(16 "In7.Cu" signal "GND3")
		(18 "In8.Cu" signal "VCC")
		(20 "In9.Cu" signal "VCC1")
		(22 "In10.Cu" signal "GND4")
		(24 "In11.Cu" signal "IN4")
		(26 "In12.Cu" signal "GND5")
		(28 "In13.Cu" signal "IN5")
		(30 "In14.Cu" signal "GND6")
		(32 "In15.Cu" signal "IN6")
		(34 "In16.Cu" signal "GND7")
		(2 "B.Cu" signal "BOTTOM")
		(9 "F.Adhes" user "F.Adhesive")
		(11 "B.Adhes" user "B.Adhesive")
		(13 "F.Paste" user "Package Geometry/Pastemask Top")
		(15 "B.Paste" user "Package Geometry/Pastemask Bottom")
		(5 "F.SilkS" user "Ref Des/Silkscreen Top")
		(7 "B.SilkS" user "Ref Des/Silkscreen Bottom")
		(1 "F.Mask" user "Board Geometry/Soldermask Top")
		(3 "B.Mask" user "Board Geometry/Soldermask Bottom")
		(17 "Dwgs.User" user "User.Drawings")
		(19 "Cmts.User" user "User.Comments")
		(21 "Eco1.User" user "User.Eco1")
		(23 "Eco2.User" user "User.Eco2")
		(25 "Edge.Cuts" user "Board Geometry/Outline")
		(27 "Margin" user)
		(31 "F.CrtYd" user "Package Geometry/Place Bound Top")
		(29 "B.CrtYd" user "Package Geometry/Place Bound Bottom")
		(35 "F.Fab" user "Ref Des/Assembly Top")
		(33 "B.Fab" user "Ref Des/Assembly Bottom")
	)
	(footprint ""
		(layer "F.Cu")
		(at 306.002182 -351.573846 90)
		(property "Reference" "PC113_4"
			(at 0 0 90)
			(layer "F.SilkS")
			(hide yes)
			(effects
				(font
					(size 1.27 1.27)
				)
			)
		)
		(property "Value" ""
			(at 0 0 90)
			(layer "F.Fab")
			(effects
				(font
					(size 1.27 1.27)
				)
			)
		)
		(duplicate_pad_numbers_are_jumpers no)
		(fp_line
			(start 0.7874 -0.4064)
			(end 0.7874 0.4064)
			(stroke
				(width 0.1524)
				(type default)
			)
			(layer "F.SilkS")
		)
		(fp_line
			(start -0.7874 -0.4064)
			(end 0.7874 -0.4064)
			(stroke
				(width 0.1524)
				(type default)
			)
			(layer "F.SilkS")
		)
		(fp_line
			(start 0.7874 0.4064)
			(end -0.7874 0.4064)
			(stroke
				(width 0.1524)
				(type default)
			)
			(layer "F.SilkS")
		)
		(fp_line
			(start -0.7874 0.4064)
			(end -0.7874 -0.4064)
			(stroke
				(width 0.1524)
				(type default)
			)
			(layer "F.SilkS")
		)
		(fp_line
			(start -0.12065 -0.305054)
			(end -0.12065 -0.2794)
			(stroke
				(width 0.1)
				(type default)
			)
			(layer "F.Fab")
		)
		(fp_line
			(start -0.67945 -0.305054)
			(end -0.12065 -0.305054)
			(stroke
				(width 0.1)
				(type default)
			)
			(layer "F.Fab")
		)
		(fp_line
			(start 0.67945 -0.3048)
			(end 0.67945 0.3048)
			(stroke
				(width 0.1)
				(type default)
			)
			(layer "F.Fab")
		)
		(fp_line
			(start 0.12065 -0.3048)
			(end 0.67945 -0.3048)
			(stroke
				(width 0.1)
				(type default)
			)
			(layer "F.Fab")
		)
		(fp_line
			(start 0.12065 -0.2794)
			(end 0.12065 -0.3048)
			(stroke
				(width 0.1)
				(type default)
			)
			(layer "F.Fab")
		)
		(fp_line
			(start -0.12065 -0.2794)
			(end 0.12065 -0.2794)
			(stroke
				(width 0.1)
				(type default)
			)
			(layer "F.Fab")
		)
		(fp_line
			(start 0.120396 0.2794)
			(end -0.12065 0.2794)
			(stroke
				(width 0.1)
				(type default)
			)
			(layer "F.Fab")
		)
		(fp_line
			(start -0.12065 0.2794)
			(end -0.12065 0.3048)
			(stroke
				(width 0.1)
				(type default)
			)
			(layer "F.Fab")
		)
		(fp_line
			(start 0.67945 0.3048)
			(end 0.120396 0.3048)
			(stroke
				(width 0.1)
				(type default)
			)
			(layer "F.Fab")
		)
		(fp_line
			(start 0.120396 0.3048)
			(end 0.120396 0.2794)
			(stroke
				(width 0.1)
				(type default)
			)
			(layer "F.Fab")
		)
		(fp_line
			(start -0.12065 0.3048)
			(end -0.67945 0.3048)
			(stroke
				(width 0.1)
				(type default)
			)
			(layer "F.Fab")
		)
		(fp_line
			(start -0.67945 0.3048)
			(end -0.67945 -0.305054)
			(stroke
				(width 0.1)
				(type default)
			)
			(layer "F.Fab")
		)
		(pad "1" smd circle
			(at -0.40005 0 90)
			(size 0 0)
			(layers "F.Cu" "F.Mask" "F.Paste")
			(net "PVDDCR_CPU1_P0_VCCS")
		)
		(pad "2" smd circle
			(at 0.40005 0 90)
			(size 0 0)
			(layers "F.Cu" "F.Mask" "F.Paste")
			(net "GND")
		)
	)
	(footprint ""
		(layer "F.Cu")
		(at 258.25958 -58.927492 90)
		(property "Reference" "R3975"
			(at 0 0 90)
			(layer "F.SilkS")
			(hide yes)
			(effects
				(font
					(size 1.27 1.27)
				)
			)
		)
		(property "Value" ""
			(at 0 0 90)
			(layer "F.Fab")
			(effects
				(font
					(size 1.27 1.27)
				)
			)
		)
		(duplicate_pad_numbers_are_jumpers no)
		(fp_line
			(start 0.7874 -0.4064)
			(end 0.7874 0.4064)
			(stroke
				(width 0.1524)
				(type default)
			)
			(layer "F.SilkS")
		)
		(fp_line
			(start -0.7874 -0.4064)
			(end 0.7874 -0.4064)
			(stroke
				(width 0.1524)
				(type default)
			)
			(layer "F.SilkS")
		)
		(fp_line
			(start 0.7874 0.4064)
			(end -0.7874 0.4064)
			(stroke
				(width 0.1524)
				(type default)
			)
			(layer "F.SilkS")
		)
		(fp_line
			(start -0.7874 0.4064)
			(end -0.7874 -0.4064)
			(stroke
				(width 0.1524)
				(type default)
			)
			(layer "F.SilkS")
		)
		(fp_line
			(start -0.12065 -0.305054)
			(end -0.12065 -0.2794)
			(stroke
				(width 0.1)
				(type default)
			)
			(layer "F.Fab")
		)
		(fp_line
			(start -0.67945 -0.305054)
			(end -0.12065 -0.305054)
			(stroke
				(width 0.1)
				(type default)
			)
			(layer "F.Fab")
		)
		(fp_line
			(start 0.67945 -0.3048)
			(end 0.67945 0.3048)
			(stroke
				(width 0.1)
				(type default)
			)
			(layer "F.Fab")
		)
		(fp_line
			(start 0.12065 -0.3048)
			(end 0.67945 -0.3048)
			(stroke
				(width 0.1)
				(type default)
			)
			(layer "F.Fab")
		)
		(fp_line
			(start 0.12065 -0.2794)
			(end 0.12065 -0.3048)
			(stroke
				(width 0.1)
				(type default)
			)
			(layer "F.Fab")
		)
		(fp_line
			(start -0.12065 -0.2794)
			(end 0.12065 -0.2794)
			(stroke
				(width 0.1)
				(type default)
			)
			(layer "F.Fab")
		)
		(fp_line
			(start 0.120396 0.2794)
			(end -0.12065 0.2794)
			(stroke
				(width 0.1)
				(type default)
			)
			(layer "F.Fab")
		)
		(fp_line
			(start -0.12065 0.2794)
			(end -0.12065 0.3048)
			(stroke
				(width 0.1)
				(type default)
			)
			(layer "F.Fab")
		)
		(fp_line
			(start 0.67945 0.3048)
			(end 0.120396 0.3048)
			(stroke
				(width 0.1)
				(type default)
			)
			(layer "F.Fab")
		)
		(fp_line
			(start 0.120396 0.3048)
			(end 0.120396 0.2794)
			(stroke
				(width 0.1)
				(type default)
			)
			(layer "F.Fab")
		)
		(fp_line
			(start -0.12065 0.3048)
			(end -0.67945 0.3048)
			(stroke
				(width 0.1)
				(type default)
			)
			(layer "F.Fab")
		)
		(fp_line
			(start -0.67945 0.3048)
			(end -0.67945 -0.305054)
			(stroke
				(width 0.1)
				(type default)
			)
			(layer "F.Fab")
		)
		(pad "1" smd rect
			(at -0.40005 0 270)
			(size 0.4572 0.508)
			(layers "F.Cu" "F.Mask" "F.Paste")
			(net "P12V_E1S_SENSE_0")
		)
		(pad "2" smd rect
			(at 0.40005 0 270)
			(size 0.4572 0.508)
			(layers "F.Cu" "F.Mask" "F.Paste")
			(net "P12V_E1S_0_ISENSE_MAM_TIC")
		)
	)
	(footprint ""
		(layer "F.Cu")
		(at 171.598844 -419.800786 180)
		(property "Reference" "C7504"
			(at 0 0 180)
			(layer "F.SilkS")
			(hide yes)
			(effects
				(font
					(size 1.27 1.27)
				)
			)
		)
		(property "Value" ""
			(at 0 0 180)
			(layer "F.Fab")
			(effects
				(font
					(size 1.27 1.27)
				)
			)
		)
		(duplicate_pad_numbers_are_jumpers no)
		(fp_line
			(start 0.299974 0.150114)
			(end -0.299974 0.150114)
			(stroke
				(width 0.1)
				(type default)
			)
			(layer "F.Fab")
		)
		(fp_line
			(start 0.299974 -0.150114)
			(end 0.299974 0.150114)
			(stroke
				(width 0.1)
				(type default)
			)
			(layer "F.Fab")
		)
		(fp_line
			(start -0.299974 0.150114)
			(end -0.299974 -0.150114)
			(stroke
				(width 0.1)
				(type default)
			)
			(layer "F.Fab")
		)
		(fp_line
			(start -0.299974 -0.150114)
			(end 0.299974 -0.150114)
			(stroke
				(width 0.1)
				(type default)
			)
			(layer "F.Fab")
		)
		(pad "1" smd rect
			(at -0.2667 0 180)
			(size 0.3048 0.381)
			(layers "F.Cu" "F.Mask" "F.Paste")
			(net "P1V8_CPU1_RT_1D")
		)
		(pad "2" smd rect
			(at 0.2667 0 180)
			(size 0.3048 0.381)
			(layers "F.Cu" "F.Mask" "F.Paste")
			(net "GND")
		)
	)
)
